# BASEBOARD_FAB2 (Tioga Pass) — schematic netlist excerpt (pin names and nets, part order shuffled) for the footprints in the layout excerpt that follows; sources: Cadence DE-HDL packaged netlist, KiCad conversion of Wiwynn_Tioga_Pass_MB.brd

C1D24  CAP_A  22.0UF 4V 20% X6S  pkg 0603V  page 209 : A = PVCCIN_CPU1 ; B = GND
R25W156  RES  3.32K 1% EMPTY  pkg 0402  page 150 : A = P3V3_STBY ; B = UART_BMC_TXD5
C829  CAP  0.22UF 16V 10% X7R  pkg 0402  page 244 : A = P3E_CPU0_PE1_PCH_TXP<13> ; B = P3E_CPU0_PE1_PCH_CON_TXP<13>

(kicad_pcb
	(version 20260206)
	(generator "pcbnew")
	(generator_version "10.0")
	(general
		(thickness 1.6)
		(legacy_teardrops no)
	)
	(paper "A4")
	(title_block
		(title "Wiwynn_Tioga_Pass_MB.brd")
		(comment 1 "Tioga Pass / footprints 1335-1337 of 4770")
	)
	(layers
		(0 "F.Cu" signal "TOP")
		(4 "In1.Cu" signal "L2GND")
		(6 "In2.Cu" signal "L3")
		(8 "In3.Cu" signal "L4GND")
		(10 "In4.Cu" signal "L5")
		(12 "In5.Cu" signal "L6GND")
		(14 "In6.Cu" signal "L7VCC")
		(16 "In7.Cu" signal "L8VCC")
		(18 "In8.Cu" signal "L9GND")
		(20 "In9.Cu" signal "L10")
		(22 "In10.Cu" signal "L11GND")
		(24 "In11.Cu" signal "L12")
		(26 "In12.Cu" signal "L13GND")
		(2 "B.Cu" signal "BOTTOM")
		(9 "F.Adhes" user "F.Adhesive")
		(11 "B.Adhes" user "B.Adhesive")
		(13 "F.Paste" user "Package Geometry/Pastemask Top")
		(15 "B.Paste" user "Package Geometry/Pastemask Bottom")
		(5 "F.SilkS" user "Ref Des/Silkscreen Top")
		(7 "B.SilkS" user "Ref Des/Silkscreen Bottom")
		(1 "F.Mask" user "Board Geometry/Soldermask Top")
		(3 "B.Mask" user "Board Geometry/Soldermask Bottom")
		(17 "Dwgs.User" user "User.Drawings")
		(19 "Cmts.User" user "User.Comments")
		(21 "Eco1.User" user "User.Eco1")
		(23 "Eco2.User" user "User.Eco2")
		(25 "Edge.Cuts" user "Board Geometry/Outline")
		(27 "Margin" user)
		(31 "F.CrtYd" user "Package Geometry/Place Bound Top")
		(29 "B.CrtYd" user "Package Geometry/Place Bound Bottom")
		(35 "F.Fab" user "Ref Des/Assembly Top")
		(33 "B.Fab" user "Ref Des/Assembly Bottom")
	)
	(footprint ""
		(layer "F.Cu")
		(at 324.5485 -120.396 -90)
		(property "Reference" "C829"
			(at -0.8382 -0.67818 270)
			(unlocked yes)
			(layer "F.SilkS")
			(effects
				(font
					(size 0.4064 0.254)
					(thickness 0.1524)
				)
				(justify left)
			)
		)
		(property "Value" ""
			(at 0 0 270)
			(layer "F.Fab")
			(effects
				(font
					(size 1.27 1.27)
				)
			)
		)
		(duplicate_pad_numbers_are_jumpers no)
		(fp_poly
			(pts
				(xy 0.3048 -0.1016) (xy 0.3048 0.9906) (xy -0.3048 0.9906) (xy -0.3048 -0.1016)
			)
			(stroke
				(width 0)
				(type default)
			)
			(fill no)
			(layer "F.CrtYd")
		)
		(fp_line
			(start -0.3048 0.9906)
			(end 0.3048 0.9906)
			(stroke
				(width 0.1)
				(type default)
			)
			(layer "F.Fab")
		)
		(fp_line
			(start 0.3048 0.9906)
			(end 0.3048 -0.1016)
			(stroke
				(width 0.1)
				(type default)
			)
			(layer "F.Fab")
		)
		(fp_line
			(start -0.3048 -0.1016)
			(end -0.3048 0.9906)
			(stroke
				(width 0.1)
				(type default)
			)
			(layer "F.Fab")
		)
		(fp_line
			(start 0.3048 -0.1016)
			(end -0.3048 -0.1016)
			(stroke
				(width 0.1)
				(type default)
			)
			(layer "F.Fab")
		)
		(pad "1" smd rect
			(at 0 0 270)
			(size 0.508 0.508)
			(layers "F.Cu" "F.Mask" "F.Paste")
			(net "P3E_CPU0_PE1_PCH_TXP<13>")
		)
		(pad "2" smd rect
			(at 0 0.889 270)
			(size 0.508 0.508)
			(layers "F.Cu" "F.Mask" "F.Paste")
			(net "P3E_CPU0_PE1_PCH_CON_TXP<13>")
		)
		(zone
			(layer "F.Cu")
			(hatch none 0.5)
			(connect_pads
				(clearance 0)
			)
			(min_thickness 0.25)
			(keepout
				(tracks allowed)
				(vias not_allowed)
				(pads allowed)
				(copperpour not_allowed)
				(footprints allowed)
			)
			(placement
				(enabled no)
				(sheetname "")
			)
			(fill
				(thermal_gap 0.5)
				(thermal_bridge_width 0.5)
				(island_removal_mode 0)
			)
			(polygon
				(pts
					(xy 324.2945 -120.65) (xy 324.2945 -120.142) (xy 323.9135 -120.142) (xy 323.9135 -120.65)
				)
			)
		)
	)
	(footprint ""
		(layer "F.Cu")
		(at 49.4284 -70.993)
		(property "Reference" "C1D24"
			(at 0 0 0)
			(layer "F.SilkS")
			(hide yes)
			(effects
				(font
					(size 1.27 1.27)
				)
			)
		)
		(property "Value" ""
			(at 0 0 0)
			(layer "F.Fab")
			(effects
				(font
					(size 1.27 1.27)
				)
			)
		)
		(duplicate_pad_numbers_are_jumpers no)
		(fp_poly
			(pts
				(xy -0.4953 -0.2032) (xy 0.4953 -0.2032) (xy 0.4953 1.6002) (xy -0.4953 1.6002)
			)
			(stroke
				(width 0)
				(type default)
			)
			(fill no)
			(layer "F.CrtYd")
		)
		(fp_line
			(start -0.4953 -0.2032)
			(end 0.4953 -0.2032)
			(stroke
				(width 0.1)
				(type default)
			)
			(layer "F.Fab")
		)
		(fp_line
			(start -0.4953 1.6002)
			(end -0.4953 -0.2032)
			(stroke
				(width 0.1)
				(type default)
			)
			(layer "F.Fab")
		)
		(fp_line
			(start 0.4953 -0.2032)
			(end 0.4953 1.6002)
			(stroke
				(width 0.1)
				(type default)
			)
			(layer "F.Fab")
		)
		(fp_line
			(start 0.4953 1.6002)
			(end -0.4953 1.6002)
			(stroke
				(width 0.1)
				(type default)
			)
			(layer "F.Fab")
		)
		(pad "1" smd rect
			(at 0 0)
			(size 0.762 0.889)
			(layers "F.Cu" "F.Mask" "F.Paste")
			(net "PVCCIN_CPU1")
		)
		(pad "2" smd rect
			(at 0 1.397)
			(size 0.762 0.889)
			(layers "F.Cu" "F.Mask" "F.Paste")
			(net "GND")
		)
		(zone
			(layer "F.Cu")
			(hatch none 0.5)
			(connect_pads
				(clearance 0)
			)
			(min_thickness 0.25)
			(keepout
				(tracks not_allowed)
				(vias allowed)
				(pads allowed)
				(copperpour not_allowed)
				(footprints allowed)
			)
			(placement
				(enabled no)
				(sheetname "")
			)
			(fill
				(thermal_gap 0.5)
				(thermal_bridge_width 0.5)
				(island_removal_mode 0)
			)
			(polygon
				(pts
					(xy 49.0474 -70.5485) (xy 49.8094 -70.5485) (xy 49.8094 -70.0405) (xy 49.0474 -70.0405)
				)
			)
		)
	)
	(footprint ""
		(layer "F.Cu")
		(at 488.3912 -22.1996 180)
		(property "Reference" "R25W156"
			(at -0.8382 -0.67818 180)
			(unlocked yes)
			(layer "F.SilkS")
			(effects
				(font
					(size 0.4064 0.254)
					(thickness 0.1524)
				)
				(justify left)
			)
		)
		(property "Value" ""
			(at 0 0 180)
			(layer "F.Fab")
			(effects
				(font
					(size 1.27 1.27)
				)
			)
		)
		(duplicate_pad_numbers_are_jumpers no)
		(fp_poly
			(pts
				(xy -0.2794 -0.1016) (xy 0.2794 -0.1016) (xy 0.2794 0.9906) (xy -0.2794 0.9906)
			)
			(stroke
				(width 0)
				(type default)
			)
			(fill no)
			(layer "F.CrtYd")
		)
		(fp_line
			(start 0.2794 0.9906)
			(end 0.2794 -0.1016)
			(stroke
				(width 0.1)
				(type default)
			)
			(layer "F.Fab")
		)
		(fp_line
			(start 0.2794 -0.1016)
			(end -0.2794 -0.1016)
			(stroke
				(width 0.1)
				(type default)
			)
			(layer "F.Fab")
		)
		(fp_line
			(start -0.2794 0.9906)
			(end 0.2794 0.9906)
			(stroke
				(width 0.1)
				(type default)
			)
			(layer "F.Fab")
		)
		(fp_line
			(start -0.2794 -0.1016)
			(end -0.2794 0.9906)
			(stroke
				(width 0.1)
				(type default)
			)
			(layer "F.Fab")
		)
		(pad "1" smd rect
			(at 0 0 180)
			(size 0.508 0.508)
			(layers "F.Cu" "F.Mask" "F.Paste")
			(net "P3V3_STBY")
		)
		(pad "2" smd rect
			(at 0 0.889 180)
			(size 0.508 0.508)
			(layers "F.Cu" "F.Mask" "F.Paste")
			(net "UART_BMC_TXD5")
		)
		(zone
			(layer "F.Cu")
			(hatch none 0.5)
			(connect_pads
				(clearance 0)
			)
			(min_thickness 0.25)
			(keepout
				(tracks not_allowed)
				(vias allowed)
				(pads allowed)
				(copperpour not_allowed)
				(footprints allowed)
			)
			(placement
				(enabled no)
				(sheetname "")
			)
			(fill
				(thermal_gap 0.5)
				(thermal_bridge_width 0.5)
				(island_removal_mode 0)
			)
			(polygon
				(pts
					(xy 488.6452 -22.8346) (xy 488.1372 -22.8346) (xy 488.1372 -22.4536) (xy 488.6452 -22.4536)
				)
			)
		)
		(zone
			(layer "F.Cu")
			(hatch none 0.5)
			(connect_pads
				(clearance 0)
			)
			(min_thickness 0.25)
			(keepout
				(tracks allowed)
				(vias not_allowed)
				(pads allowed)
				(copperpour not_allowed)
				(footprints allowed)
			)
			(placement
				(enabled no)
				(sheetname "")
			)
			(fill
				(thermal_gap 0.5)
				(thermal_bridge_width 0.5)
				(island_removal_mode 0)
			)
			(polygon
				(pts
					(xy 488.6452 -22.4536) (xy 488.1372 -22.4536) (xy 488.1372 -22.8346) (xy 488.6452 -22.8346)
				)
			)
		)
	)
)
